#ISCELL
  mstr_misc dns *
  *
#ISCELL
  pure_quanta quanta_title_block_c *
  *
#ISCELL
  pure_quanta_power cad_note *
  *
#ISCELL
  pure_quanta_power design_note *
  *
#ISCELL
  standard offpage *
  page297_i1
#ISCELL
  pure_quanta_power universal_power *
  page297_i100
#CELL
  pure_quanta q_res *
  page297_i101
#CELL
  pure_quanta q_res *
  page297_i102
#ISCELL
  standard offpage *
  page297_i103
#ISCELL
  pure_quanta_power universal_power *
  page297_i104
#CELL
  pure_quanta q_res *
  page297_i105
#CELL
  pure_quanta q_res *
  page297_i106
#ISCELL
  pure_quanta_power universal_power *
  page297_i107
#ISCELL
  standard offpage *
  page297_i14
#ISCELL
  standard offpage *
  page297_i15
#ISCELL
  standard offpage *
  page297_i16
#ISCELL
  standard offpage *
  page297_i17
#ISCELL
  standard offpage *
  page297_i18
#CELL
  pure_quanta q_res *
  page297_i2
#ISCELL
  pure_quanta_power universal_gnd *
  page297_i20
#ISCELL
  standard tap *
  page297_i21
#ISCELL
  standard tap *
  page297_i22
#ISCELL
  standard tap *
  page297_i23
#ISCELL
  standard tap *
  page297_i24
#ISCELL
  standard tap *
  page297_i25
#ISCELL
  standard tap *
  page297_i26
#ISCELL
  standard tap *
  page297_i27
#ISCELL
  standard tap *
  page297_i28
#ISCELL
  standard offpage *
  page297_i29
#ISCELL
  pure_quanta_power universal_gnd *
  page297_i3
#CELL
  pure_quanta q_res *
  page297_i30
#CELL
  pure_quanta q_res *
  page297_i31
#ISCELL
  pure_quanta_power universal_power *
  page297_i33
#ISCELL
  pure_quanta_power universal_power *
  page297_i34
#ISCELL
  pure_quanta_power universal_gnd *
  page297_i35
#CELL
  pure_quanta q_cap *
  page297_i36
#CELL
  pure_quanta q_res *
  page297_i37
#CELL
  pure_quanta q_res *
  page297_i38
#CELL
  pure_quanta 74lvc2g07dw7 *
  page297_i4
#CELL
  pure_quanta q_res *
  page297_i40
#ISCELL
  standard offpage *
  page297_i41
#ISCELL
  standard offpage *
  page297_i42
#ISCELL
  pure_quanta_power universal_power *
  page297_i43
#ISCELL
  pure_quanta_power universal_gnd *
  page297_i5
#ISCELL
  pure_quanta_power universal_gnd *
  page297_i52
#ISCELL
  standard tap *
  page297_i54
#ISCELL
  standard tap *
  page297_i55
#ISCELL
  standard tap *
  page297_i56
#ISCELL
  standard tap *
  page297_i57
#ISCELL
  standard tap *
  page297_i58
#ISCELL
  standard tap *
  page297_i59
#CELL
  pure_quanta q_res *
  page297_i6
#ISCELL
  standard tap *
  page297_i60
#ISCELL
  standard tap *
  page297_i61
#ISCELL
  pure_quanta_power universal_power *
  page297_i64
#CELL
  pure_quanta q_cap *
  page297_i66
#CELL
  pure_quanta q_cap *
  page297_i67
#CELL
  pure_quanta q_cap *
  page297_i68
#ISCELL
  pure_quanta_power universal_power *
  page297_i69
#CELL
  pure_quanta q_res *
  page297_i7
#ISCELL
  standard offpage *
  page297_i70
#ISCELL
  standard offpage *
  page297_i71
#ISCELL
  standard offpage *
  page297_i72
#ISCELL
  pure_quanta_power universal_gnd *
  page297_i73
#CELL
  pure_quanta q_cap *
  page297_i74
#CELL
  pure_quanta q_res *
  page297_i75
#ISCELL
  pure_quanta_power universal_gnd *
  page297_i76
#ISCELL
  pure_quanta_power universal_power *
  page297_i78
#CELL
  pure_quanta q_res *
  page297_i79
#ISCELL
  pure_quanta_power universal_power *
  page297_i8
#ISCELL
  standard offpage *
  page297_i80
#ISCELL
  standard offpage *
  page297_i81
#ISCELL
  standard offpage *
  page297_i82
#ISCELL
  standard offpage *
  page297_i83
#ISCELL
  standard offpage *
  page297_i85
#ISCELL
  pure_quanta_power universal_gnd *
  page297_i86
#CELL
  pure_quanta q_cap *
  page297_i87
#CELL
  pure_quanta q_cap *
  page297_i88
#ISCELL
  pure_quanta_power universal_power *
  page297_i89
#ISCELL
  standard offpage *
  page297_i9
#CELL
  pure_quanta sconn56_123276793 *
  page297_i90
#ISCELL
  pure_quanta_power universal_gnd *
  page297_i91
#ISCELL
  pure_quanta_power universal_gnd *
  page297_i92
#ISCELL
  standard offpage *
  page297_i93
#CELL
  pure_quanta q_res *
  page297_i94
#CELL
  pure_quanta q_res *
  page297_i95
#ISCELL
  pure_quanta_power universal_gnd *
  page297_i96
#CELL
  pure_quanta 74lvc1g17gw *
  page297_i97
#ISCELL
  pure_quanta_power universal_gnd *
  page297_i98
#CELL
  pure_quanta q_cap *
  page297_i99
